FILE_TYPE = CONNECTIVITY;
{Allegro Design Entry HDL 17.4-2019 S026 (4007227) 1/17/2022}
"PAGE_NUMBER" = 299;
0"NC";
1"P3V3_AUX\g";
2"GND\g";
3"P3V3_AUX\g";
4"P3V3_AUX\g";
5"GND\g";
6"P3V3_AUX\g";
7"GND\g";
8"GND\g";
9"GND\g";
10"P3V3_AUX\g";
11"GND\g";
12"GND\g";
13"P3V3_AUX\g";
14"GND\g";
15"P3V3_AUX\g";
16"GND\g";
17"P3V3_AUX\g";
18"GND\g";
19"GND\g";
20"P3V3_AUX\g";
21"GND\g";
22"P3V3_AUX\g";
23"GND\g";
24"P3V3_AUX\g";
25"GND\g";
26"GND\g";
27"P3V3_AUX\g";
28"GND\g";
29"P3V3_AUX\g";
30"GND\g";
31"P3V3_AUX\g";
32"GND\g";
33"GND\g";
34"P3V3_AUX\g";
35"GND\g";
36"GND\g";
37"P3V3_AUX\g";
38"GND\g";
39"P3V3_AUX\g";
40"P3V3_AUX\g";
41"GND\g";
42"P3V3_AUX\g";
43"P3V3_AUX\g";
44"GND\g";
45"GND\g";
46"GND\g";
47"GND\g";
48"GND\g";
49"P3V3_AUX\g";
50"GPU_WP_HW_CTRL_N";
51"GPU_HMC_PRSNT_N";
52"GPU_HMC_PRSNT";
53"GPU_BASE_HMC_READY";
54"GPU_BASE_HMC_READY_N";
55"GPU_FPGA_OVERT_N";
56"GPU_FPGA_THERM_OVERT";
57"GPU_FPGA_THERM_OVERT_N";
58"GPU_FPGA_OVERT";
59"GPU_FPGA_OVERT_ISO_N";
60"GPU_BASE_HMC_READY_ISO";
61"GPU_FPGA_THERM_OVERT_ISO_N";
62"GPU_HMC_PRSNT_ISO_N";
63"GPU_FPGA_EROT_FATALERR_ISO_N";
64"GPU_FPGA_EROT_FATALERR_N";
65"GPU_FPGA_EROT_FATALERR";
66"GPU_PRSNT_N_ISO";
67"GPU_PRSNT";
68"GPU_PRSNT_N";
69"GPU_WP_HW_CTRL_ISO_N";
70"GPU_WP_HW_CTRL_ISO";
%"UNIVERSAL_POWER"
"1","(-2925,1500)","0","pure_quanta_power","I10";
;
HDL_POWER"P3V3_AUX"
CDS_LIB"pure_quanta_power";
"A"1;
%"UNIVERSAL_GND"
"1","(-2950,1950)","0","pure_quanta_power","I11";
;
CDS_LIB"pure_quanta_power"
HDL_POWER"GND";
"A"2;
%"Q_CAP"
"1","(100,1300)","0","pure_quanta","I129";
;
LOCATION"C1975"
$SEC"1"
CDS_SEC"1"
VALUE"0.1UF"
VOLTAGE"25V"
TOLERANCE"10%"
MATERIAL"X7R"
PACK_TYPE"0402"
CDS_LIB"pure_quanta"
PART_NUMBER"CH4104K1B00";
"B"
$PN"2"45;
"A"
$PN"1"62;
%"Q_RES"
"2","(-2975,2600)","0","pure_quanta","I130";
;
LOCATION"R3429"
$SEC"1"
CDS_SEC"1"
WATTAGE"1/16W"
TOLERANCE"1%"
VALUE"100K"
PACK_TYPE"0402LF"
MATERIAL"EMPTY"
CDS_LIB"pure_quanta"
PART_NUMBER"CS41002FB09";
"A"
$PN"1"3;
"B"
$PN"2"53;
%"Q_RES"
"2","(-2950,2125)","0","pure_quanta","I131";
;
LOCATION"R3463"
$SEC"1"
CDS_SEC"1"
WATTAGE"1/16W"
PACK_TYPE"0402LF"
MATERIAL"CHIP"
VALUE"54.9K"
TOLERANCE"1%"
CDS_LIB"pure_quanta"
PART_NUMBER"CS35492FB03";
"A"
$PN"1"53;
"B"
$PN"2"2;
%"Q_RES"
"2","(-2925,1250)","0","pure_quanta","I132";
;
LOCATION"R3465"
$SEC"1"
CDS_SEC"1"
MATERIAL"CHIP"
VALUE"10K"
TOLERANCE"1%"
PACK_TYPE"0402LF"
WATTAGE"1/16W"
CDS_LIB"pure_quanta"
PART_NUMBER"CS31002FB08";
"A"
$PN"1"1;
"B"
$PN"2"51;
%"Q_RES"
"2","(-2900,775)","0","pure_quanta","I133";
;
LOCATION"R3431"
$SEC"1"
CDS_SEC"1"
PACK_TYPE"0402LF"
WATTAGE"1/16W"
MATERIAL"EMPTY"
VALUE"100K"
TOLERANCE"1%"
CDS_LIB"pure_quanta"
PART_NUMBER"CS41002FB09";
"A"
$PN"1"51;
"B"
$PN"2"47;
%"Q_RES"
"2","(-2975,-375)","0","pure_quanta","I134";
;
LOCATION"R3464"
$SEC"1"
CDS_SEC"1"
PACK_TYPE"0402LF"
WATTAGE"1/16W"
TOLERANCE"1%"
MATERIAL"CHIP"
VALUE"54.9K"
CDS_LIB"pure_quanta"
PART_NUMBER"CS35492FB03";
"A"
$PN"1"39;
"B"
$PN"2"55;
%"UNIVERSAL_POWER"
"1","(-2975,2850)","0","pure_quanta_power","I15";
;
HDL_POWER"P3V3_AUX"
CDS_LIB"pure_quanta_power";
"A"3;
%"UNIVERSAL_POWER"
"1","(3875,2475)","0","pure_quanta_power","I150";
;
HDL_POWER"P3V3_AUX"
CDS_LIB"pure_quanta_power";
"A"4;
%"Q_CAP"
"1","(4775,1550)","0","pure_quanta","I152";
;
LOCATION"C1978"
$SEC"1"
CDS_SEC"1"
VALUE"0.1UF"
PACK_TYPE"0402"
MATERIAL"X7R"
VOLTAGE"25V"
TOLERANCE"10%"
CDS_LIB"pure_quanta"
PART_NUMBER"CH4104K1B00";
"B"
$PN"2"5;
"A"
$PN"1"66;
%"UNIVERSAL_GND"
"1","(4775,1350)","0","pure_quanta_power","I153";
;
CDS_LIB"pure_quanta_power"
HDL_POWER"GND";
"A"5;
%"Q_RES"
"2","(3875,2175)","0","pure_quanta","I154";
;
LOCATION"R3475"
$SEC"1"
CDS_SEC"1"
WATTAGE"1/16W"
MATERIAL"CHIP"
PACK_TYPE"0402LF"
VALUE"100K"
TOLERANCE"1%"
CDS_LIB"pure_quanta"
PART_NUMBER"CS41002FB09";
"A"
$PN"1"4;
"B"
$PN"2"66;
%"UNIVERSAL_POWER"
"1","(2950,2225)","0","pure_quanta_power","I155";
;
HDL_POWER"P3V3_AUX"
CDS_LIB"pure_quanta_power";
"A"6;
%"UNIVERSAL_GND"
"1","(3875,1350)","0","pure_quanta_power","I156";
;
CDS_LIB"pure_quanta_power"
HDL_POWER"GND";
"A"7;
%"MOSFET_NCH_DUAL"
"2","(3825,1725)","0","pure_quanta","I157";
;
LOCATION"Q107"
$SEC"2"
CDS_SEC"2"
VALUE"PJT138K"
PART_TYPE"SMLF"
MATERIAL"IC"
CDS_LMAN_SYM_OUTLINE"-150,150,150,-150"
NEEDS_NO_SIZE"TRUE"
CDS_LIB"pure_quanta"
PART_NUMBER"BAM138K0003";
"S2"
$PN"4"7;
"G2"
$PN"5"67;
"D2"
$PN"3"66;
%"Q_RES"
"2","(2950,1925)","0","pure_quanta","I158";
;
LOCATION"R3474"
$SEC"1"
CDS_SEC"1"
TOLERANCE"5%"
VALUE"4.7K"
WATTAGE"1/16W"
MATERIAL"CHIP"
PACK_TYPE"0402LF"
CDS_LIB"pure_quanta"
PART_NUMBER"CS24702JB10";
"A"
$PN"1"6;
"B"
$PN"2"67;
%"UNIVERSAL_GND"
"1","(2950,1075)","0","pure_quanta_power","I159";
;
CDS_LIB"pure_quanta_power"
HDL_POWER"GND";
"A"8;
%"UNIVERSAL_GND"
"1","(-2975,3325)","0","pure_quanta_power","I16";
;
CDS_LIB"pure_quanta_power"
HDL_POWER"GND";
"A"9;
%"MOSFET_NCH_DUAL"
"1","(2900,1450)","0","pure_quanta","I160";
;
LOCATION"Q107"
$SEC"1"
CDS_SEC"1"
MATERIAL"IC"
PART_TYPE"SMLF"
VALUE"PJT138K"
CDS_LMAN_SYM_OUTLINE"-150,150,150,-150"
NEEDS_NO_SIZE"TRUE"
CDS_LIB"pure_quanta"
PART_NUMBER"BAM138K0003";
"D1"
$PN"6"67;
"G1"
$PN"2"68;
"S1"
$PN"1"8;
%"UNIVERSAL_POWER"
"1","(1700,1925)","0","pure_quanta_power","I161";
;
HDL_POWER"P3V3_AUX"
CDS_LIB"pure_quanta_power";
"A"10;
%"Q_RES"
"2","(1725,1200)","0","pure_quanta","I163";
;
LOCATION"R3473"
$SEC"1"
CDS_SEC"1"
PACK_TYPE"0402LF"
WATTAGE"1/16W"
MATERIAL"EMPTY"
TOLERANCE"1%"
VALUE"100K"
CDS_LIB"pure_quanta"
PART_NUMBER"CS41002FB09";
"A"
$PN"1"68;
"B"
$PN"2"11;
%"UNIVERSAL_GND"
"1","(1725,1000)","0","pure_quanta_power","I164";
;
CDS_LIB"pure_quanta_power"
HDL_POWER"GND";
"A"11;
%"Q_RES"
"2","(1700,1625)","0","pure_quanta","I166";
;
LOCATION"R3487"
$SEC"1"
CDS_SEC"1"
PACK_TYPE"0402LF"
VALUE"10K"
WATTAGE"1/16W"
MATERIAL"CHIP"
TOLERANCE"1%"
CDS_LIB"pure_quanta"
PART_NUMBER"CS31002FB08";
"A"
$PN"1"10;
"B"
$PN"2"68;
%"Q_RES"
"2","(-3000,4000)","0","pure_quanta","I167";
;
LOCATION"R3498"
$SEC"1"
CDS_SEC"1"
VALUE"54.9K"
TOLERANCE"1%"
MATERIAL"CHIP"
WATTAGE"1/16W"
PACK_TYPE"0402LF"
CDS_LIB"pure_quanta"
PART_NUMBER"CS35492FB03";
"A"
$PN"1"27;
"B"
$PN"2"57;
%"MOSFET_NCH_DUAL"
"2","(3850,0)","0","pure_quanta","I168";
;
LOCATION"Q108"
$SEC"2"
CDS_SEC"2"
MATERIAL"IC"
PART_TYPE"SMLF"
VALUE"PJT138K"
CDS_LIB"pure_quanta"
NEEDS_NO_SIZE"TRUE"
CDS_LMAN_SYM_OUTLINE"-150,150,150,-150"
PART_NUMBER"BAM138K0003";
"S2"
$PN"4"14;
"G2"
$PN"5"65;
"D2"
$PN"3"63;
%"MOSFET_NCH_DUAL"
"1","(2925,-275)","0","pure_quanta","I169";
;
LOCATION"Q108"
$SEC"1"
CDS_SEC"1"
MATERIAL"IC"
PART_TYPE"SMLF"
VALUE"PJT138K"
CDS_LIB"pure_quanta"
NEEDS_NO_SIZE"TRUE"
CDS_LMAN_SYM_OUTLINE"-150,150,150,-150"
PART_NUMBER"BAM138K0003";
"D1"
$PN"6"65;
"G1"
$PN"2"64;
"S1"
$PN"1"16;
%"Q_RES"
"2","(-2975,3525)","0","pure_quanta","I17";
;
LOCATION"R3428"
$SEC"1"
CDS_SEC"1"
TOLERANCE"1%"
VALUE"100K"
MATERIAL"EMPTY"
WATTAGE"1/16W"
PACK_TYPE"0402LF"
CDS_LIB"pure_quanta"
PART_NUMBER"CS41002FB09";
"A"
$PN"1"57;
"B"
$PN"2"9;
%"Q_CAP"
"1","(4800,-175)","0","pure_quanta","I171";
;
LOCATION"C1988"
$SEC"1"
CDS_SEC"1"
VOLTAGE"25V"
TOLERANCE"10%"
MATERIAL"X7R"
PACK_TYPE"0402"
VALUE"0.1UF"
CDS_LIB"pure_quanta"
PART_NUMBER"CH4104K1B00";
"B"
$PN"2"12;
"A"
$PN"1"63;
%"UNIVERSAL_GND"
"1","(4800,-375)","0","pure_quanta_power","I172";
;
CDS_LIB"pure_quanta_power"
HDL_POWER"GND";
"A"12;
%"UNIVERSAL_POWER"
"1","(3900,750)","0","pure_quanta_power","I173";
;
HDL_POWER"P3V3_AUX"
CDS_LIB"pure_quanta_power";
"A"13;
%"Q_RES"
"2","(3900,450)","0","pure_quanta","I174";
;
LOCATION"R3504"
$SEC"1"
CDS_SEC"1"
TOLERANCE"1%"
MATERIAL"CHIP"
VALUE"100K"
WATTAGE"1/16W"
PACK_TYPE"0402LF"
CDS_LIB"pure_quanta"
PART_NUMBER"CS41002FB09";
"A"
$PN"1"13;
"B"
$PN"2"63;
%"UNIVERSAL_GND"
"1","(3900,-375)","0","pure_quanta_power","I175";
;
CDS_LIB"pure_quanta_power"
HDL_POWER"GND";
"A"14;
%"UNIVERSAL_POWER"
"1","(2975,500)","0","pure_quanta_power","I176";
;
HDL_POWER"P3V3_AUX"
CDS_LIB"pure_quanta_power";
"A"15;
%"Q_RES"
"2","(2975,200)","0","pure_quanta","I177";
;
LOCATION"R3503"
$SEC"1"
CDS_SEC"1"
WATTAGE"1/16W"
VALUE"4.7K"
TOLERANCE"5%"
MATERIAL"CHIP"
PACK_TYPE"0402LF"
CDS_LIB"pure_quanta"
PART_NUMBER"CS24702JB10";
"A"
$PN"1"15;
"B"
$PN"2"65;
%"UNIVERSAL_GND"
"1","(2975,-650)","0","pure_quanta_power","I178";
;
CDS_LIB"pure_quanta_power"
HDL_POWER"GND";
"A"16;
%"UNIVERSAL_POWER"
"1","(1725,200)","0","pure_quanta_power","I179";
;
HDL_POWER"P3V3_AUX"
CDS_LIB"pure_quanta_power";
"A"17;
%"Q_RES"
"2","(1750,-525)","0","pure_quanta","I181";
;
LOCATION"R3502"
$SEC"1"
CDS_SEC"1"
MATERIAL"EMPTY"
WATTAGE"1/16W"
TOLERANCE"1%"
VALUE"100K"
PACK_TYPE"0402LF"
CDS_LIB"pure_quanta"
PART_NUMBER"CS41002FB09";
"A"
$PN"1"64;
"B"
$PN"2"18;
%"UNIVERSAL_GND"
"1","(1750,-725)","0","pure_quanta_power","I182";
;
CDS_LIB"pure_quanta_power"
HDL_POWER"GND";
"A"18;
%"Q_RES"
"2","(1725,-100)","0","pure_quanta","I184";
;
LOCATION"R3525"
$SEC"1"
CDS_SEC"1"
PACK_TYPE"0402LF"
VALUE"54.9K"
TOLERANCE"1%"
MATERIAL"CHIP"
WATTAGE"1/16W"
CDS_LIB"pure_quanta"
PART_NUMBER"CS35492FB03";
"A"
$PN"1"17;
"B"
$PN"2"64;
%"UNIVERSAL_GND"
"1","(1600,2775)","0","pure_quanta_power","I186";
;
CDS_LIB"pure_quanta_power"
HDL_POWER"GND";
"A"19;
%"Q_RES"
"2","(1600,3050)","0","pure_quanta","I187";
;
LOCATION"R3471"
$SEC"1"
CDS_SEC"1"
VALUE"10K"
WATTAGE"1/16W"
TOLERANCE"1%"
MATERIAL"EMPTY"
PACK_TYPE"0402LF"
CDS_LIB"pure_quanta"
PART_NUMBER"CS31002FB08";
"A"
$PN"1"50;
"B"
$PN"2"19;
%"UNIVERSAL_POWER"
"1","(1575,3850)","0","pure_quanta_power","I190";
;
HDL_POWER"P3V3_AUX"
CDS_LIB"pure_quanta_power";
"A"20;
%"UNIVERSAL_GND"
"1","(2750,3000)","0","pure_quanta_power","I191";
;
CDS_LIB"pure_quanta_power"
HDL_POWER"GND";
"A"21;
%"Q_RES"
"2","(2750,3875)","0","pure_quanta","I192";
;
LOCATION"R9043"
$SEC"1"
CDS_SEC"1"
VALUE"4.7K"
WATTAGE"1/16W"
PACK_TYPE"0402LF"
MATERIAL"CHIP"
TOLERANCE"5%"
CDS_LIB"pure_quanta"
PART_NUMBER"CS24702JB10";
"A"
$PN"1"22;
"B"
$PN"2"70;
%"UNIVERSAL_POWER"
"1","(2750,4175)","0","pure_quanta_power","I193";
;
HDL_POWER"P3V3_AUX"
CDS_LIB"pure_quanta_power";
"A"22;
%"UNIVERSAL_GND"
"1","(3725,3300)","0","pure_quanta_power","I194";
;
CDS_LIB"pure_quanta_power"
HDL_POWER"GND";
"A"23;
%"Q_RES"
"2","(3725,4175)","0","pure_quanta","I195";
;
LOCATION"R9044"
$SEC"1"
CDS_SEC"1"
MATERIAL"EMPTY"
PACK_TYPE"0402LF"
VALUE"4.7K"
WATTAGE"1/16W"
TOLERANCE"1%"
CDS_LIB"pure_quanta"
PART_NUMBER"CS24702FB06";
"A"
$PN"1"24;
"B"
$PN"2"69;
%"UNIVERSAL_POWER"
"1","(3725,4475)","0","pure_quanta_power","I196";
;
HDL_POWER"P3V3_AUX"
CDS_LIB"pure_quanta_power";
"A"24;
%"UNIVERSAL_GND"
"1","(4600,3400)","0","pure_quanta_power","I197";
;
CDS_LIB"pure_quanta_power"
HDL_POWER"GND";
"A"25;
%"Q_RES"
"1","(4600,3675)","1","pure_quanta","I198";
;
LOCATION"R3472"
$SEC"1"
CDS_SEC"1"
VALUE"0"
MATERIAL"EMPTY"
TOLERANCE"5%"
PACK_TYPE"0402LF"
CDS_LIB"pure_quanta"
WATTAGE"1/16W"
PART_NUMBER"CS00002JB13";
"B"
$PN"2"69;
"A"
$PN"1"25;
%"UNIVERSAL_GND"
"1","(-2950,-1000)","0","pure_quanta_power","I2";
;
CDS_LIB"pure_quanta_power"
HDL_POWER"GND";
"A"26;
%"UNIVERSAL_POWER"
"1","(-3000,4250)","0","pure_quanta_power","I20";
;
HDL_POWER"P3V3_AUX"
CDS_LIB"pure_quanta_power";
"A"27;
%"MOSFET_NCH_DUAL"
"2","(3675,3675)","0","pure_quanta","I200";
;
LOCATION"Q106"
$SEC"2"
CDS_SEC"2"
MATERIAL"IC"
VALUE"PJT138K"
PART_TYPE"SMLF"
NEEDS_NO_SIZE"TRUE"
CDS_LMAN_SYM_OUTLINE"-150,150,150,-150"
CDS_LIB"pure_quanta"
PART_NUMBER"BAM138K0003";
"S2"
$PN"4"23;
"G2"
$PN"5"70;
"D2"
$PN"3"69;
%"MOSFET_NCH_DUAL"
"1","(2700,3375)","0","pure_quanta","I201";
;
LOCATION"Q106"
$SEC"1"
CDS_SEC"1"
VALUE"PJT138K"
PART_TYPE"SMLF"
MATERIAL"IC"
NEEDS_NO_SIZE"TRUE"
CDS_LMAN_SYM_OUTLINE"-150,150,150,-150"
CDS_LIB"pure_quanta"
PART_NUMBER"BAM138K0003";
"D1"
$PN"6"70;
"G1"
$PN"2"50;
"S1"
$PN"1"21;
%"Q_RES"
"2","(1575,3600)","0","pure_quanta","I202";
;
LOCATION"R3470"
$SEC"1"
CDS_SEC"1"
VALUE"1K"
TOLERANCE"1%"
PACK_TYPE"0402LF"
MATERIAL"CHIP"
WATTAGE"1/16W"
CDS_LIB"pure_quanta"
PART_NUMBER"CS21002FB06";
"A"
$PN"1"20;
"B"
$PN"2"50;
%"MOSFET_NCH_DUAL"
"1","(-1775,-550)","0","pure_quanta","I21";
;
LOCATION"Q104"
$SEC"1"
CDS_SEC"1"
VALUE"PJT138K"
MATERIAL"IC"
PART_TYPE"SMLF"
CDS_LIB"pure_quanta"
NEEDS_NO_SIZE"TRUE"
CDS_LMAN_SYM_OUTLINE"-150,150,150,-150"
PART_NUMBER"BAM138K0003";
"D1"
$PN"6"58;
"G1"
$PN"2"55;
"S1"
$PN"1"28;
%"UNIVERSAL_GND"
"1","(-1725,-925)","0","pure_quanta_power","I22";
;
CDS_LIB"pure_quanta_power"
HDL_POWER"GND";
"A"28;
%"Q_RES"
"2","(-1725,-75)","0","pure_quanta","I23";
;
LOCATION"R3435"
$SEC"1"
CDS_SEC"1"
WATTAGE"1/16W"
MATERIAL"CHIP"
VALUE"4.7K"
TOLERANCE"5%"
PACK_TYPE"0402LF"
CDS_LIB"pure_quanta"
PART_NUMBER"CS24702JB10";
"A"
$PN"1"29;
"B"
$PN"2"58;
%"UNIVERSAL_POWER"
"1","(-1725,225)","0","pure_quanta_power","I24";
;
HDL_POWER"P3V3_AUX"
CDS_LIB"pure_quanta_power";
"A"29;
%"UNIVERSAL_GND"
"1","(-800,-650)","0","pure_quanta_power","I25";
;
CDS_LIB"pure_quanta_power"
HDL_POWER"GND";
"A"30;
%"MOSFET_NCH_DUAL"
"2","(-850,-275)","0","pure_quanta","I26";
;
LOCATION"Q104"
$SEC"2"
CDS_SEC"2"
VALUE"PJT138K"
PART_TYPE"SMLF"
MATERIAL"IC"
CDS_LMAN_SYM_OUTLINE"-150,150,150,-150"
NEEDS_NO_SIZE"TRUE"
CDS_LIB"pure_quanta"
PART_NUMBER"BAM138K0003";
"S2"
$PN"4"30;
"G2"
$PN"5"58;
"D2"
$PN"3"59;
%"Q_RES"
"2","(-800,175)","0","pure_quanta","I27";
;
LOCATION"R3437"
$SEC"1"
CDS_SEC"1"
TOLERANCE"1%"
VALUE"100K"
MATERIAL"CHIP"
WATTAGE"1/16W"
PACK_TYPE"0402LF"
CDS_LIB"pure_quanta"
PART_NUMBER"CS41002FB09";
"A"
$PN"1"31;
"B"
$PN"2"59;
%"UNIVERSAL_POWER"
"1","(-800,475)","0","pure_quanta_power","I28";
;
HDL_POWER"P3V3_AUX"
CDS_LIB"pure_quanta_power";
"A"31;
%"UNIVERSAL_GND"
"1","(100,-650)","0","pure_quanta_power","I29";
;
CDS_LIB"pure_quanta_power"
HDL_POWER"GND";
"A"32;
%"Q_RES"
"2","(-2950,-800)","0","pure_quanta","I3";
;
LOCATION"R3430"
$SEC"1"
CDS_SEC"1"
MATERIAL"EMPTY"
WATTAGE"1/16W"
TOLERANCE"1%"
VALUE"100K"
PACK_TYPE"0402LF"
CDS_LIB"pure_quanta"
PART_NUMBER"CS41002FB09";
"A"
$PN"1"55;
"B"
$PN"2"26;
%"Q_CAP"
"1","(100,-450)","0","pure_quanta","I30";
;
LOCATION"C1976"
$SEC"1"
CDS_SEC"1"
PACK_TYPE"0402"
MATERIAL"X7R"
TOLERANCE"10%"
VALUE"0.1UF"
VOLTAGE"25V"
CDS_LIB"pure_quanta"
PART_NUMBER"CH4104K1B00";
"B"
$PN"2"32;
"A"
$PN"1"59;
%"MOSFET_NCH_DUAL"
"1","(-1800,1025)","0","pure_quanta","I37";
;
LOCATION"Q103"
$SEC"1"
CDS_SEC"1"
PART_TYPE"SMLF"
VALUE"PJT138K"
MATERIAL"IC"
CDS_LIB"pure_quanta"
NEEDS_NO_SIZE"TRUE"
CDS_LMAN_SYM_OUTLINE"-150,150,150,-150"
PART_NUMBER"BAM138K0003";
"D1"
$PN"6"52;
"G1"
$PN"2"51;
"S1"
$PN"1"33;
%"UNIVERSAL_GND"
"1","(-1750,650)","0","pure_quanta_power","I38";
;
CDS_LIB"pure_quanta_power"
HDL_POWER"GND";
"A"33;
%"Q_RES"
"2","(-1750,1475)","0","pure_quanta","I39";
;
LOCATION"R3434"
$SEC"1"
CDS_SEC"1"
VALUE"4.7K"
TOLERANCE"5%"
PACK_TYPE"0402LF"
MATERIAL"CHIP"
WATTAGE"1/16W"
CDS_LIB"pure_quanta"
PART_NUMBER"CS24702JB10";
"A"
$PN"1"34;
"B"
$PN"2"52;
%"MOSFET_NCH_DUAL"
"1","(-1800,2375)","0","pure_quanta","I40";
;
LOCATION"Q102"
$SEC"1"
CDS_SEC"1"
VALUE"PJT138K"
MATERIAL"IC"
PART_TYPE"SMLF"
CDS_LMAN_SYM_OUTLINE"-150,150,150,-150"
NEEDS_NO_SIZE"TRUE"
CDS_LIB"pure_quanta"
PART_NUMBER"BAM138K0003";
"D1"
$PN"6"54;
"G1"
$PN"2"53;
"S1"
$PN"1"35;
%"UNIVERSAL_POWER"
"1","(-1750,1775)","0","pure_quanta_power","I41";
;
HDL_POWER"P3V3_AUX"
CDS_LIB"pure_quanta_power";
"A"34;
%"UNIVERSAL_GND"
"1","(-1750,2000)","0","pure_quanta_power","I42";
;
CDS_LIB"pure_quanta_power"
HDL_POWER"GND";
"A"35;
%"MOSFET_NCH_DUAL"
"2","(-850,1300)","0","pure_quanta","I43";
;
LOCATION"Q103"
$SEC"2"
CDS_SEC"2"
VALUE"PJT138K"
MATERIAL"IC"
PART_TYPE"SMLF"
CDS_LMAN_SYM_OUTLINE"-150,150,150,-150"
NEEDS_NO_SIZE"TRUE"
CDS_LIB"pure_quanta"
PART_NUMBER"BAM138K0003";
"S2"
$PN"4"36;
"G2"
$PN"5"52;
"D2"
$PN"3"62;
%"UNIVERSAL_GND"
"1","(-800,925)","0","pure_quanta_power","I44";
;
CDS_LIB"pure_quanta_power"
HDL_POWER"GND";
"A"36;
%"Q_RES"
"2","(-800,1725)","0","pure_quanta","I45";
;
LOCATION"R3436"
$SEC"1"
CDS_SEC"1"
TOLERANCE"1%"
VALUE"100K"
MATERIAL"CHIP"
PACK_TYPE"0402LF"
WATTAGE"1/16W"
CDS_LIB"pure_quanta"
PART_NUMBER"CS41002FB09";
"A"
$PN"1"37;
"B"
$PN"2"62;
%"UNIVERSAL_POWER"
"1","(-800,2025)","0","pure_quanta_power","I46";
;
HDL_POWER"P3V3_AUX"
CDS_LIB"pure_quanta_power";
"A"37;
%"UNIVERSAL_GND"
"1","(-775,2300)","0","pure_quanta_power","I47";
;
CDS_LIB"pure_quanta_power"
HDL_POWER"GND";
"A"38;
%"MOSFET_NCH_DUAL"
"2","(-825,2675)","0","pure_quanta","I48";
;
LOCATION"Q102"
$SEC"2"
CDS_SEC"2"
MATERIAL"IC"
VALUE"PJT138K"
PART_TYPE"SMLF"
CDS_LIB"pure_quanta"
NEEDS_NO_SIZE"TRUE"
CDS_LMAN_SYM_OUTLINE"-150,150,150,-150"
PART_NUMBER"BAM138K0003";
"S2"
$PN"4"38;
"G2"
$PN"5"54;
"D2"
$PN"3"60;
%"Q_RES"
"2","(-1775,2825)","0","pure_quanta","I49";
;
LOCATION"R3433"
$SEC"1"
CDS_SEC"1"
MATERIAL"CHIP"
PACK_TYPE"0402LF"
WATTAGE"1/16W"
TOLERANCE"5%"
VALUE"4.7K"
CDS_LIB"pure_quanta"
PART_NUMBER"CS24702JB10";
"A"
$PN"1"40;
"B"
$PN"2"54;
%"UNIVERSAL_POWER"
"1","(-2975,-75)","0","pure_quanta_power","I5";
;
HDL_POWER"P3V3_AUX"
CDS_LIB"pure_quanta_power";
"A"39;
%"UNIVERSAL_POWER"
"1","(-1775,3125)","0","pure_quanta_power","I50";
;
HDL_POWER"P3V3_AUX"
CDS_LIB"pure_quanta_power";
"A"40;
%"UNIVERSAL_GND"
"1","(-1825,3400)","0","pure_quanta_power","I51";
;
CDS_LIB"pure_quanta_power"
HDL_POWER"GND";
"A"41;
%"MOSFET_NCH_DUAL"
"1","(-1875,3775)","0","pure_quanta","I52";
;
LOCATION"Q101"
$SEC"1"
CDS_SEC"1"
MATERIAL"IC"
PART_TYPE"SMLF"
VALUE"PJT138K"
CDS_LMAN_SYM_OUTLINE"-150,150,150,-150"
NEEDS_NO_SIZE"TRUE"
CDS_LIB"pure_quanta"
PART_NUMBER"BAM138K0003";
"D1"
$PN"6"56;
"G1"
$PN"2"57;
"S1"
$PN"1"41;
%"Q_RES"
"2","(-1825,4375)","0","pure_quanta","I53";
;
LOCATION"R3432"
$SEC"1"
CDS_SEC"1"
PACK_TYPE"0402LF"
TOLERANCE"5%"
WATTAGE"1/16W"
VALUE"4.7K"
MATERIAL"CHIP"
CDS_LIB"pure_quanta"
PART_NUMBER"CS24702JB10";
"A"
$PN"1"42;
"B"
$PN"2"56;
%"UNIVERSAL_POWER"
"1","(-1825,4600)","0","pure_quanta_power","I54";
;
HDL_POWER"P3V3_AUX"
CDS_LIB"pure_quanta_power";
"A"42;
%"Q_RES"
"2","(-775,3100)","0","pure_quanta","I55";
;
LOCATION"R3438"
$SEC"1"
CDS_SEC"1"
TOLERANCE"1%"
VALUE"100K"
MATERIAL"CHIP"
PACK_TYPE"0402LF"
WATTAGE"1/16W"
CDS_LIB"pure_quanta"
PART_NUMBER"CS41002FB09";
"A"
$PN"1"43;
"B"
$PN"2"60;
%"UNIVERSAL_POWER"
"1","(-775,3325)","0","pure_quanta_power","I56";
;
HDL_POWER"P3V3_AUX"
CDS_LIB"pure_quanta_power";
"A"43;
%"MOSFET_NCH_DUAL"
"2","(-725,4075)","0","pure_quanta","I57";
;
LOCATION"Q101"
$SEC"2"
CDS_SEC"2"
VALUE"PJT138K"
PART_TYPE"SMLF"
MATERIAL"IC"
CDS_LIB"pure_quanta"
NEEDS_NO_SIZE"TRUE"
CDS_LMAN_SYM_OUTLINE"-150,150,150,-150"
PART_NUMBER"BAM138K0003";
"S2"
$PN"4"44;
"G2"
$PN"5"56;
"D2"
$PN"3"61;
%"UNIVERSAL_GND"
"1","(-675,3700)","0","pure_quanta_power","I58";
;
CDS_LIB"pure_quanta_power"
HDL_POWER"GND";
"A"44;
%"Q_RES"
"2","(-675,4500)","2","pure_quanta","I59";
;
LOCATION"R3439"
$SEC"1"
CDS_SEC"1"
PACK_TYPE"0402LF"
MATERIAL"CHIP"
WATTAGE"1/16W"
VALUE"100K"
TOLERANCE"1%"
CDS_LIB"pure_quanta"
PART_NUMBER"CS41002FB09";
"A"
$PN"1"49;
"B"
$PN"2"61;
%"UNIVERSAL_GND"
"1","(100,1100)","0","pure_quanta_power","I60";
;
CDS_LIB"pure_quanta_power"
HDL_POWER"GND";
"A"45;
%"UNIVERSAL_GND"
"1","(50,2450)","0","pure_quanta_power","I61";
;
CDS_LIB"pure_quanta_power"
HDL_POWER"GND";
"A"46;
%"UNIVERSAL_GND"
"1","(-2900,600)","0","pure_quanta_power","I7";
;
CDS_LIB"pure_quanta_power"
HDL_POWER"GND";
"A"47;
%"Q_CAP"
"1","(50,2650)","0","pure_quanta","I71";
;
LOCATION"C1973"
$SEC"1"
CDS_SEC"1"
VALUE"0.1UF"
VOLTAGE"25V"
TOLERANCE"10%"
MATERIAL"X7R"
PACK_TYPE"0402"
CDS_LIB"pure_quanta"
PART_NUMBER"CH4104K1B00";
"B"
$PN"2"46;
"A"
$PN"1"60;
%"UNIVERSAL_GND"
"1","(100,3825)","0","pure_quanta_power","I73";
;
CDS_LIB"pure_quanta_power"
HDL_POWER"GND";
"A"48;
%"Q_CAP"
"1","(100,4025)","0","pure_quanta","I74";
;
LOCATION"C1974"
$SEC"1"
CDS_SEC"1"
VOLTAGE"25V"
PACK_TYPE"0402"
MATERIAL"X7R"
TOLERANCE"10%"
VALUE"0.1UF"
CDS_LIB"pure_quanta"
PART_NUMBER"CH4104K1B00";
"B"
$PN"2"48;
"A"
$PN"1"61;
%"UNIVERSAL_POWER"
"1","(-675,4725)","0","pure_quanta_power","I83";
;
HDL_POWER"P3V3_AUX"
CDS_LIB"pure_quanta_power";
"A"49;
END.
